(kicad_pcb
	(version 20260206)
	(generator "pcbnew")
	(generator_version "10.0")
	(general
		(thickness 1.6)
		(legacy_teardrops no)
	)
	(paper "A4")
	(title_block
		(title "01162023_DA0F0TEBIF0_F0T_Expander_BD_F_brd_V02_OCP.brd")
		(comment 1 "Grand Teton / footprint 5622 of 9728 (PEX2), pads 1-116 of 2397")
	)
	(layers
		(0 "F.Cu" signal "TOP")
		(4 "In1.Cu" signal "GND")
		(6 "In2.Cu" signal "VCC")
		(8 "In3.Cu" signal "VCC1")
		(10 "In4.Cu" signal "GND1")
		(12 "In5.Cu" signal "IN1")
		(14 "In6.Cu" signal "GND2")
		(16 "In7.Cu" signal "IN2")
		(18 "In8.Cu" signal "GND3")
		(20 "In9.Cu" signal "IN3")
		(22 "In10.Cu" signal "GND4")
		(24 "In11.Cu" signal "IN4")
		(26 "In12.Cu" signal "GND5")
		(28 "In13.Cu" signal "IN5")
		(30 "In14.Cu" signal "GND6")
		(32 "In15.Cu" signal "IN6")
		(34 "In16.Cu" signal "GND7")
		(2 "B.Cu" signal "BOTTOM")
		(9 "F.Adhes" user "F.Adhesive")
		(11 "B.Adhes" user "B.Adhesive")
		(13 "F.Paste" user "Package Geometry/Pastemask Top")
		(15 "B.Paste" user "Package Geometry/Pastemask Bottom")
		(5 "F.SilkS" user "Ref Des/Silkscreen Top")
		(7 "B.SilkS" user "Ref Des/Silkscreen Bottom")
		(1 "F.Mask" user "Board Geometry/Soldermask Top")
		(3 "B.Mask" user "Board Geometry/Soldermask Bottom")
		(17 "Dwgs.User" user "User.Drawings")
		(19 "Cmts.User" user "User.Comments")
		(21 "Eco1.User" user "User.Eco1")
		(23 "Eco2.User" user "User.Eco2")
		(25 "Edge.Cuts" user "Board Geometry/Outline")
		(27 "Margin" user)
		(31 "F.CrtYd" user "Package Geometry/Place Bound Top")
		(29 "B.CrtYd" user "Package Geometry/Place Bound Bottom")
		(35 "F.Fab" user "Ref Des/Assembly Top")
		(33 "B.Fab" user "Ref Des/Assembly Bottom")
	)
	(footprint ""
		(layer "F.Cu")
		(at 291.84981 -295.89984)
		(property "Reference" "PEX2"
			(at -3.35153 35.56762 0)
			(unlocked yes)
			(layer "F.SilkS")
			(effects
				(font
					(size 2.032 1.524)
					(thickness 0.1524)
				)
				(justify left)
			)
		)
		(property "Value" ""
			(at 0 0 0)
			(layer "F.Fab")
			(effects
				(font
					(size 1.27 1.27)
				)
			)
		)
		(duplicate_pad_numbers_are_jumpers no)
		(pad "A2" smd circle
			(at -21.850096 -22.800056)
			(size 0.4572 0.4572)
			(layers "F.Cu" "F.Mask" "F.Paste")
			(net "GND")
		)
		(pad "A3" smd circle
			(at -20.899882 -22.800056)
			(size 0.4572 0.4572)
			(layers "F.Cu" "F.Mask" "F.Paste")
			(net "P5E_PEX2_STN7_RX_DN<123>")
		)
		(pad "A4" smd circle
			(at -19.949922 -22.800056)
			(size 0.4572 0.4572)
			(layers "F.Cu" "F.Mask" "F.Paste")
			(net "GND")
		)
		(pad "A5" smd circle
			(at -18.999962 -22.800056)
			(size 0.4572 0.4572)
			(layers "F.Cu" "F.Mask" "F.Paste")
			(net "P5E_PEX2_STN7_RX_DN<125>")
		)
		(pad "A6" smd circle
			(at -18.050002 -22.800056)
			(size 0.4572 0.4572)
			(layers "F.Cu" "F.Mask" "F.Paste")
			(net "GND")
		)
		(pad "A7" smd circle
			(at -17.100042 -22.800056)
			(size 0.4572 0.4572)
			(layers "F.Cu" "F.Mask" "F.Paste")
			(net "P5E_PEX2_STN7_RX_DN<127>")
		)
		(pad "A8" smd circle
			(at -16.150082 -22.800056)
			(size 0.4572 0.4572)
			(layers "F.Cu" "F.Mask" "F.Paste")
			(net "GND")
		)
		(pad "A9" smd circle
			(at -15.200122 -22.800056)
			(size 0.4572 0.4572)
			(layers "F.Cu" "F.Mask" "F.Paste")
			(net "P5E_PEX2_STN6_RX_DN<110>")
		)
		(pad "A10" smd circle
			(at -14.249908 -22.800056)
			(size 0.4572 0.4572)
			(layers "F.Cu" "F.Mask" "F.Paste")
			(net "GND")
		)
		(pad "A11" smd circle
			(at -13.299948 -22.800056)
			(size 0.4572 0.4572)
			(layers "F.Cu" "F.Mask" "F.Paste")
			(net "P5E_PEX2_STN6_RX_DN<108>")
		)
		(pad "A12" smd circle
			(at -12.349988 -22.800056)
			(size 0.4572 0.4572)
			(layers "F.Cu" "F.Mask" "F.Paste")
			(net "GND")
		)
		(pad "A13" smd circle
			(at -11.400028 -22.800056)
			(size 0.4572 0.4572)
			(layers "F.Cu" "F.Mask" "F.Paste")
			(net "P5E_PEX2_STN6_RX_DN<106>")
		)
		(pad "A14" smd circle
			(at -10.450068 -22.800056)
			(size 0.4572 0.4572)
			(layers "F.Cu" "F.Mask" "F.Paste")
			(net "GND")
		)
		(pad "A15" smd circle
			(at -9.500108 -22.800056)
			(size 0.4572 0.4572)
			(layers "F.Cu" "F.Mask" "F.Paste")
			(net "P5E_PEX2_STN6_RX_DN<104>")
		)
		(pad "A16" smd circle
			(at -8.549894 -22.800056)
			(size 0.4572 0.4572)
			(layers "F.Cu" "F.Mask" "F.Paste")
			(net "GND")
		)
		(pad "A17" smd circle
			(at -7.599934 -22.800056)
			(size 0.4572 0.4572)
			(layers "F.Cu" "F.Mask" "F.Paste")
			(net "P5E_PEX2_STN6_RX_DN<102>")
		)
		(pad "A18" smd circle
			(at -6.649974 -22.800056)
			(size 0.4572 0.4572)
			(layers "F.Cu" "F.Mask" "F.Paste")
			(net "GND")
		)
		(pad "A19" smd circle
			(at -5.700014 -22.800056)
			(size 0.4572 0.4572)
			(layers "F.Cu" "F.Mask" "F.Paste")
			(net "P5E_PEX2_STN6_RX_DN<100>")
		)
		(pad "A20" smd circle
			(at -4.750054 -22.800056)
			(size 0.4572 0.4572)
			(layers "F.Cu" "F.Mask" "F.Paste")
			(net "GND")
		)
		(pad "A21" smd circle
			(at -3.800094 -22.800056)
			(size 0.4572 0.4572)
			(layers "F.Cu" "F.Mask" "F.Paste")
			(net "P5E_PEX2_STN6_RX_DN<98>")
		)
		(pad "A22" smd circle
			(at -2.84988 -22.800056)
			(size 0.4572 0.4572)
			(layers "F.Cu" "F.Mask" "F.Paste")
			(net "GND")
		)
		(pad "A23" smd circle
			(at -1.89992 -22.800056)
			(size 0.4572 0.4572)
			(layers "F.Cu" "F.Mask" "F.Paste")
			(net "P5E_PEX2_STN6_RX_DN<96>")
		)
		(pad "A24" smd circle
			(at -0.94996 -22.800056)
			(size 0.4572 0.4572)
			(layers "F.Cu" "F.Mask" "F.Paste")
			(net "GND")
		)
		(pad "A25" smd circle
			(at 0 -22.800056)
			(size 0.4572 0.4572)
			(layers "F.Cu" "F.Mask" "F.Paste")
			(net "P5E_PEX2_STN5_RX_DN<81>")
		)
		(pad "A26" smd circle
			(at 0.94996 -22.800056)
			(size 0.4572 0.4572)
			(layers "F.Cu" "F.Mask" "F.Paste")
			(net "GND")
		)
		(pad "A27" smd circle
			(at 1.89992 -22.800056)
			(size 0.4572 0.4572)
			(layers "F.Cu" "F.Mask" "F.Paste")
			(net "P5E_PEX2_STN5_RX_DN<83>")
		)
		(pad "A28" smd circle
			(at 2.84988 -22.800056)
			(size 0.4572 0.4572)
			(layers "F.Cu" "F.Mask" "F.Paste")
			(net "GND")
		)
		(pad "A29" smd circle
			(at 3.800094 -22.800056)
			(size 0.4572 0.4572)
			(layers "F.Cu" "F.Mask" "F.Paste")
			(net "P5E_PEX2_STN5_RX_DN<85>")
		)
		(pad "A30" smd circle
			(at 4.750054 -22.800056)
			(size 0.4572 0.4572)
			(layers "F.Cu" "F.Mask" "F.Paste")
			(net "GND")
		)
		(pad "A31" smd circle
			(at 5.700014 -22.800056)
			(size 0.4572 0.4572)
			(layers "F.Cu" "F.Mask" "F.Paste")
			(net "P5E_PEX2_STN5_RX_DN<87>")
		)
		(pad "A32" smd circle
			(at 6.649974 -22.800056)
			(size 0.4572 0.4572)
			(layers "F.Cu" "F.Mask" "F.Paste")
			(net "GND")
		)
		(pad "A33" smd circle
			(at 7.599934 -22.800056)
			(size 0.4572 0.4572)
			(layers "F.Cu" "F.Mask" "F.Paste")
			(net "P5E_PEX2_STN5_RX_DN<89>")
		)
		(pad "A34" smd circle
			(at 8.549894 -22.800056)
			(size 0.4572 0.4572)
			(layers "F.Cu" "F.Mask" "F.Paste")
			(net "GND")
		)
		(pad "A35" smd circle
			(at 9.500108 -22.800056)
			(size 0.4572 0.4572)
			(layers "F.Cu" "F.Mask" "F.Paste")
			(net "P5E_PEX2_STN5_RX_DN<91>")
		)
		(pad "A36" smd circle
			(at 10.450068 -22.800056)
			(size 0.4572 0.4572)
			(layers "F.Cu" "F.Mask" "F.Paste")
			(net "GND")
		)
		(pad "A37" smd circle
			(at 11.400028 -22.800056)
			(size 0.4572 0.4572)
			(layers "F.Cu" "F.Mask" "F.Paste")
			(net "P5E_PEX2_STN5_RX_DN<93>")
		)
		(pad "A38" smd circle
			(at 12.349988 -22.800056)
			(size 0.4572 0.4572)
			(layers "F.Cu" "F.Mask" "F.Paste")
			(net "GND")
		)
		(pad "A39" smd circle
			(at 13.299948 -22.800056)
			(size 0.4572 0.4572)
			(layers "F.Cu" "F.Mask" "F.Paste")
			(net "P5E_PEX2_STN5_RX_DN<95>")
		)
		(pad "A40" smd circle
			(at 14.249908 -22.800056)
			(size 0.4572 0.4572)
			(layers "F.Cu" "F.Mask" "F.Paste")
			(net "GND")
		)
		(pad "A41" smd circle
			(at 15.200122 -22.800056)
			(size 0.4572 0.4572)
			(layers "F.Cu" "F.Mask" "F.Paste")
			(net "P5E_PEX2_STN4_RX_DN<78>")
		)
		(pad "A42" smd circle
			(at 16.150082 -22.800056)
			(size 0.4572 0.4572)
			(layers "F.Cu" "F.Mask" "F.Paste")
			(net "GND")
		)
		(pad "A43" smd circle
			(at 17.100042 -22.800056)
			(size 0.4572 0.4572)
			(layers "F.Cu" "F.Mask" "F.Paste")
			(net "P5E_PEX2_STN4_RX_DN<76>")
		)
		(pad "A44" smd circle
			(at 18.050002 -22.800056)
			(size 0.4572 0.4572)
			(layers "F.Cu" "F.Mask" "F.Paste")
			(net "GND")
		)
		(pad "A45" smd circle
			(at 18.999962 -22.800056)
			(size 0.4572 0.4572)
			(layers "F.Cu" "F.Mask" "F.Paste")
			(net "P5E_PEX2_STN4_RX_DN<74>")
		)
		(pad "A46" smd circle
			(at 19.949922 -22.800056)
			(size 0.4572 0.4572)
			(layers "F.Cu" "F.Mask" "F.Paste")
			(net "GND")
		)
		(pad "A47" smd circle
			(at 20.899882 -22.800056)
			(size 0.4572 0.4572)
			(layers "F.Cu" "F.Mask" "F.Paste")
			(net "P5E_PEX2_STN4_RX_DN<72>")
		)
		(pad "A48" smd circle
			(at 21.850096 -22.800056)
			(size 0.4572 0.4572)
			(layers "F.Cu" "F.Mask" "F.Paste")
			(net "GND")
		)
		(pad "AA1" smd circle
			(at -22.800056 -3.800094)
			(size 0.4572 0.4572)
			(layers "F.Cu" "F.Mask" "F.Paste")
			(net "CLK_100M_PEX2_REF_R_DN")
		)
		(pad "AA2" smd circle
			(at -21.850096 -3.800094)
			(size 0.4572 0.4572)
			(layers "F.Cu" "F.Mask" "F.Paste")
			(net "CLK_100M_PEX2_REF_R_DP")
		)
		(pad "AA3" smd circle
			(at -20.899882 -3.800094)
			(size 0.4572 0.4572)
			(layers "F.Cu" "F.Mask" "F.Paste")
			(net "GND")
		)
		(pad "AA4" smd circle
			(at -19.949922 -3.800094)
			(size 0.4572 0.4572)
			(layers "F.Cu" "F.Mask" "F.Paste")
			(net "GND")
		)
		(pad "AA5" smd circle
			(at -18.999962 -3.800094)
			(size 0.4572 0.4572)
			(layers "F.Cu" "F.Mask" "F.Paste")
			(net "GND")
		)
		(pad "AA6" smd circle
			(at -18.050002 -3.800094)
			(size 0.4572 0.4572)
			(layers "F.Cu" "F.Mask" "F.Paste")
			(net "GND")
		)
		(pad "AA7" smd circle
			(at -17.100042 -3.800094)
			(size 0.4572 0.4572)
			(layers "F.Cu" "F.Mask" "F.Paste")
			(net "GND")
		)
		(pad "AA8" smd circle
			(at -16.150082 -3.800094)
			(size 0.4572 0.4572)
			(layers "F.Cu" "F.Mask" "F.Paste")
			(net "GND")
		)
		(pad "AA9" smd circle
			(at -15.200122 -3.800094)
			(size 0.4572 0.4572)
			(layers "F.Cu" "F.Mask" "F.Paste")
			(net "GND")
		)
		(pad "AA10" smd circle
			(at -14.249908 -3.800094)
			(size 0.4572 0.4572)
			(layers "F.Cu" "F.Mask" "F.Paste")
			(net "P1V8_VDDA_PEX2")
		)
		(pad "AA11" smd circle
			(at -13.299948 -3.800094)
			(size 0.4572 0.4572)
			(layers "F.Cu" "F.Mask" "F.Paste")
			(net "GND")
		)
		(pad "AA12" smd circle
			(at -12.349988 -3.800094)
			(size 0.4572 0.4572)
			(layers "F.Cu" "F.Mask" "F.Paste")
			(net "GND")
		)
		(pad "AA13" smd circle
			(at -11.400028 -3.800094)
			(size 0.4572 0.4572)
			(layers "F.Cu" "F.Mask" "F.Paste")
			(net "PCEPLL0_VDDA18_PEX2")
		)
		(pad "AA14" smd circle
			(at -10.450068 -3.800094)
			(size 0.4572 0.4572)
			(layers "F.Cu" "F.Mask" "F.Paste")
			(net "GND")
		)
		(pad "AA15" smd circle
			(at -9.500108 -3.800094)
			(size 0.4572 0.4572)
			(layers "F.Cu" "F.Mask" "F.Paste")
			(net "P0V8_PEX2")
		)
		(pad "AA16" smd circle
			(at -8.549894 -3.800094)
			(size 0.4572 0.4572)
			(layers "F.Cu" "F.Mask" "F.Paste")
			(net "GND")
		)
		(pad "AA17" smd circle
			(at -7.599934 -3.800094)
			(size 0.4572 0.4572)
			(layers "F.Cu" "F.Mask" "F.Paste")
			(net "GND")
		)
		(pad "AA18" smd circle
			(at -6.649974 -3.800094)
			(size 0.4572 0.4572)
			(layers "F.Cu" "F.Mask" "F.Paste")
			(net "GND")
		)
		(pad "AA19" smd circle
			(at -5.700014 -3.800094)
			(size 0.4572 0.4572)
			(layers "F.Cu" "F.Mask" "F.Paste")
			(net "GND")
		)
		(pad "AA20" smd circle
			(at -4.750054 -3.800094)
			(size 0.4572 0.4572)
			(layers "F.Cu" "F.Mask" "F.Paste")
			(net "GND")
		)
		(pad "AA21" smd circle
			(at -3.800094 -3.800094)
			(size 0.4572 0.4572)
			(layers "F.Cu" "F.Mask" "F.Paste")
			(net "GND")
		)
		(pad "AA22" smd circle
			(at -2.84988 -3.800094)
			(size 0.4572 0.4572)
			(layers "F.Cu" "F.Mask" "F.Paste")
			(net "GND")
		)
		(pad "AA23" smd circle
			(at -1.89992 -3.800094)
			(size 0.4572 0.4572)
			(layers "F.Cu" "F.Mask" "F.Paste")
			(net "GND")
		)
		(pad "AA24" smd circle
			(at -0.94996 -3.800094)
			(size 0.4572 0.4572)
			(layers "F.Cu" "F.Mask" "F.Paste")
			(net "GND")
		)
		(pad "AA25" smd circle
			(at 0 -3.800094)
			(size 0.4572 0.4572)
			(layers "F.Cu" "F.Mask" "F.Paste")
			(net "GND")
		)
		(pad "AA26" smd circle
			(at 0.94996 -3.800094)
			(size 0.4572 0.4572)
			(layers "F.Cu" "F.Mask" "F.Paste")
			(net "GND")
		)
		(pad "AA27" smd circle
			(at 1.89992 -3.800094)
			(size 0.4572 0.4572)
			(layers "F.Cu" "F.Mask" "F.Paste")
			(net "GND")
		)
		(pad "AA28" smd circle
			(at 2.84988 -3.800094)
			(size 0.4572 0.4572)
			(layers "F.Cu" "F.Mask" "F.Paste")
			(net "GND")
		)
		(pad "AA29" smd circle
			(at 3.800094 -3.800094)
			(size 0.4572 0.4572)
			(layers "F.Cu" "F.Mask" "F.Paste")
			(net "GND")
		)
		(pad "AA30" smd circle
			(at 4.750054 -3.800094)
			(size 0.4572 0.4572)
			(layers "F.Cu" "F.Mask" "F.Paste")
			(net "GND")
		)
		(pad "AA31" smd circle
			(at 5.700014 -3.800094)
			(size 0.4572 0.4572)
			(layers "F.Cu" "F.Mask" "F.Paste")
			(net "GND")
		)
		(pad "AA32" smd circle
			(at 6.649974 -3.800094)
			(size 0.4572 0.4572)
			(layers "F.Cu" "F.Mask" "F.Paste")
			(net "GND")
		)
		(pad "AA33" smd circle
			(at 7.599934 -3.800094)
			(size 0.4572 0.4572)
			(layers "F.Cu" "F.Mask" "F.Paste")
			(net "GND")
		)
		(pad "AA34" smd circle
			(at 8.549894 -3.800094)
			(size 0.4572 0.4572)
			(layers "F.Cu" "F.Mask" "F.Paste")
			(net "P1V8_VDDA_PEX2")
		)
		(pad "AA35" smd circle
			(at 9.500108 -3.800094)
			(size 0.4572 0.4572)
			(layers "F.Cu" "F.Mask" "F.Paste")
			(net "Net_516")
		)
		(pad "AA36" smd circle
			(at 10.450068 -3.800094)
			(size 0.4572 0.4572)
			(layers "F.Cu" "F.Mask" "F.Paste")
			(net "GND")
		)
		(pad "AA37" smd circle
			(at 11.400028 -3.800094)
			(size 0.4572 0.4572)
			(layers "F.Cu" "F.Mask" "F.Paste")
			(net "P1V8_VDDA_PEX2")
		)
		(pad "AA38" smd circle
			(at 12.349988 -3.800094)
			(size 0.4572 0.4572)
			(layers "F.Cu" "F.Mask" "F.Paste")
			(net "GND")
		)
		(pad "AA39" smd circle
			(at 13.299948 -3.800094)
			(size 0.4572 0.4572)
			(layers "F.Cu" "F.Mask" "F.Paste")
			(net "PEX2_ADCTEMP_VINP1")
		)
		(pad "AA40" smd circle
			(at 14.249908 -3.800094)
			(size 0.4572 0.4572)
			(layers "F.Cu" "F.Mask" "F.Paste")
			(net "GND")
		)
		(pad "AA41" smd circle
			(at 15.200122 -3.800094)
			(size 0.4572 0.4572)
			(layers "F.Cu" "F.Mask" "F.Paste")
			(net "GND")
		)
		(pad "AA42" smd circle
			(at 16.150082 -3.800094)
			(size 0.4572 0.4572)
			(layers "F.Cu" "F.Mask" "F.Paste")
			(net "GND")
		)
		(pad "AA43" smd circle
			(at 17.100042 -3.800094)
			(size 0.4572 0.4572)
			(layers "F.Cu" "F.Mask" "F.Paste")
			(net "Net_1681")
		)
		(pad "AA44" smd circle
			(at 18.050002 -3.800094)
			(size 0.4572 0.4572)
			(layers "F.Cu" "F.Mask" "F.Paste")
			(net "Net_1694")
		)
		(pad "AA45" smd circle
			(at 18.999962 -3.800094)
			(size 0.4572 0.4572)
			(layers "F.Cu" "F.Mask" "F.Paste")
			(net "GND")
		)
		(pad "AA46" smd circle
			(at 19.949922 -3.800094)
			(size 0.4572 0.4572)
			(layers "F.Cu" "F.Mask" "F.Paste")
			(net "Net_1562")
		)
		(pad "AA47" smd circle
			(at 20.899882 -3.800094)
			(size 0.4572 0.4572)
			(layers "F.Cu" "F.Mask" "F.Paste")
			(net "Net_1581")
		)
		(pad "AA48" smd circle
			(at 21.850096 -3.800094)
			(size 0.4572 0.4572)
			(layers "F.Cu" "F.Mask" "F.Paste")
			(net "GND")
		)
		(pad "AA49" smd circle
			(at 22.800056 -3.800094)
			(size 0.4572 0.4572)
			(layers "F.Cu" "F.Mask" "F.Paste")
			(net "GND")
		)
		(pad "AB1" smd circle
			(at -22.800056 -2.84988)
			(size 0.4572 0.4572)
			(layers "F.Cu" "F.Mask" "F.Paste")
			(net "GND")
		)
		(pad "AB2" smd circle
			(at -21.850096 -2.84988)
			(size 0.4572 0.4572)
			(layers "F.Cu" "F.Mask" "F.Paste")
			(net "GND")
		)
		(pad "AB3" smd circle
			(at -20.899882 -2.84988)
			(size 0.4572 0.4572)
			(layers "F.Cu" "F.Mask" "F.Paste")
			(net "GND")
		)
		(pad "AB4" smd circle
			(at -19.949922 -2.84988)
			(size 0.4572 0.4572)
			(layers "F.Cu" "F.Mask" "F.Paste")
			(net "CLK_100M_DB800ZL_PEX2_S0_R_DN")
		)
		(pad "AB5" smd circle
			(at -18.999962 -2.84988)
			(size 0.4572 0.4572)
			(layers "F.Cu" "F.Mask" "F.Paste")
			(net "CLK_100M_DB800ZL_PEX2_S0_R_DP")
		)
		(pad "AB6" smd circle
			(at -18.050002 -2.84988)
			(size 0.4572 0.4572)
			(layers "F.Cu" "F.Mask" "F.Paste")
			(net "GND")
		)
		(pad "AB7" smd circle
			(at -17.100042 -2.84988)
			(size 0.4572 0.4572)
			(layers "F.Cu" "F.Mask" "F.Paste")
			(net "Net_5396")
		)
		(pad "AB8" smd circle
			(at -16.150082 -2.84988)
			(size 0.4572 0.4572)
			(layers "F.Cu" "F.Mask" "F.Paste")
			(net "Net_5395")
		)
		(pad "AB9" smd circle
			(at -15.200122 -2.84988)
			(size 0.4572 0.4572)
			(layers "F.Cu" "F.Mask" "F.Paste")
			(net "GND")
		)
		(pad "AB10" smd circle
			(at -14.249908 -2.84988)
			(size 0.4572 0.4572)
			(layers "F.Cu" "F.Mask" "F.Paste")
			(net "P1V8_VDDA_PEX2")
		)
		(pad "AB11" smd circle
			(at -13.299948 -2.84988)
			(size 0.4572 0.4572)
			(layers "F.Cu" "F.Mask" "F.Paste")
			(net "GND")
		)
		(pad "AB12" smd circle
			(at -12.349988 -2.84988)
			(size 0.4572 0.4572)
			(layers "F.Cu" "F.Mask" "F.Paste")
			(net "PCEPLL1_VDDA18_PEX2")
		)
		(pad "AB13" smd circle
			(at -11.400028 -2.84988)
			(size 0.4572 0.4572)
			(layers "F.Cu" "F.Mask" "F.Paste")
			(net "GND")
		)
		(pad "AB14" smd circle
			(at -10.450068 -2.84988)
			(size 0.4572 0.4572)
			(layers "F.Cu" "F.Mask" "F.Paste")
			(net "P0V8_PEX2")
		)
		(pad "AB15" smd circle
			(at -9.500108 -2.84988)
			(size 0.4572 0.4572)
			(layers "F.Cu" "F.Mask" "F.Paste")
			(net "GND")
		)
		(pad "AB16" smd circle
			(at -8.549894 -2.84988)
			(size 0.4572 0.4572)
			(layers "F.Cu" "F.Mask" "F.Paste")
			(net "P0V8_SERDES_VDDA_PEX2")
		)
		(pad "AB17" smd circle
			(at -7.599934 -2.84988)
			(size 0.4572 0.4572)
			(layers "F.Cu" "F.Mask" "F.Paste")
			(net "P0V8_SERDES_VDDA_PEX2")
		)
		(pad "AB18" smd circle
			(at -6.649974 -2.84988)
			(size 0.4572 0.4572)
			(layers "F.Cu" "F.Mask" "F.Paste")
			(net "P0V8_SERDES_VDDA_PEX2")
		)
		(pad "AB19" smd circle
			(at -5.700014 -2.84988)
			(size 0.4572 0.4572)
			(layers "F.Cu" "F.Mask" "F.Paste")
			(net "P0V8_SERDES_VDDA_PEX2")
		)
		(pad "AB20" smd circle
			(at -4.750054 -2.84988)
			(size 0.4572 0.4572)
			(layers "F.Cu" "F.Mask" "F.Paste")
			(net "P0V8_SERDES_VDDA_PEX2")
		)
	)
)
